FILE_TYPE = MULTI_PHYS_TABLE;

PART 'Q_CAP_DIFFBUS'

{========================================================================================}
:VALUE             | VOLTAGE | TOLERANCE | PACK_TYPE | MATERIAL | PART_NUMBER        = STANDARD        | LIFECYCLE      | ASS_PART | PART_NUMBER   | JEDEC_TYPE       | DESCRIPTION                                         | MANUFTR | MANUF_PN            | RD_CMPLS_LVL | CMPLS_LVL | CLASS      | DIP_SMD | FROM_PJ        | DATA                             | FP_ECN                      | EE_CHECK_LIST | PSL | STATUS | CREATOR | CREATEDAY  ;
{========================================================================================}
 'DIFF BUS_0.1UF'  | '16V'   | '10%'     | 'C0402'   | 'X7R'    | 'SP_CH4103K1B09'(!) = 'End of Design' | 'Comp-Approve' | 'SELASS' | 'CH4103K1B09' |'C0402_DIFF-BUS'| 'CAP CHIP 0.1U 16V(10%.X7R.0402)SEL-ASS'            | 'MUR'   | 'GRM155R71C104K'    | 'PF(V1)'     | 'PF(V1)'  | 'DISCRETE' | ''      | 'T2R-YAO-HSUN' | 'MUR_LF_CAP SERIES_20100122.pdf' | '0402 SERIES_LL34.xls'      | ''            | ''  | ''     | ''      | '20131204'
 'DIFF BUS_0.1UF'  | '16V'   | '10%'     | 'C0402'   | 'EMPTY'  | 'SP_CH4103K1B09'(!) = 'End of Design' | 'Comp-Approve' | 'SELASS' | 'CH4103K1B09' |'C0402_DIFF-BUS'| 'CAP CHIP 0.1U 16V(10%.X7R.0402)SEL-ASS'            | 'MUR'   | 'GRM155R71C104K'    | 'PF(V1)'     | 'PF(V1)'  | 'DISCRETE' | ''      | 'T2R-YAO-HSUN' | 'MUR_LF_CAP SERIES_20100122.pdf' | '0402 SERIES_LL34.xls'      | ''            | ''  | ''     | ''      | '20131204'
 'DIFF BUS_0.22UF' | '16V'   | '10%'     | 'C0402'   | 'X7R'    | 'SP_CH4223K1B00'(!) = 'End of Design' | 'Comp-Approve' | ''       | 'CH4223K1B00' |'C0402_DIFF-BUS'| 'CAP CHIP 0.22U 16V(10%.X7R.0402)_FOR DIFF BUS'     | 'MUR'   | 'GRM155R71C224K'    | 'EU(V1)'     | ''        | 'DISCRETE' | ''      | 'T2R-YAO-HSUN' | 'AC Coupling.msg'                | '0402 SERIES_LL34.xls'      | ''            | ''  | ''     | ''      | '20131204'
 'DIFF BUS_0.22UF' | '16V'   | '10%'     | 'C0402'   | 'EMPTY'  | 'SP_CH4223K1B00'(!) = 'End of Design' | 'Comp-Approve' | ''       | 'CH4223K1B00' |'C0402_DIFF-BUS'| 'CAP CHIP 0.22U 16V(10%.X7R.0402)_FOR DIFF BUS'     | 'MUR'   | 'GRM155R71C224K'    | 'EU(V1)'     | ''        | 'DISCRETE' | ''      | 'T2R-YAO-HSUN' | 'AC Coupling.msg'                | '0402 SERIES_LL34.xls'      | ''            | ''  | ''     | ''      | '20131204'
 'DIFF BUS_0.1UF'  | '16V'   | '10%'     | 'C0402'   | 'X7R'    | 'SP_CH4103K1B08'(!) = ''              | ''             | ''       | 'CH4103K1B08' |'C0402_DIFF-BUS'| 'CAP CHIP 0.1U 16V(10%.X7R.0402)_FOR DIFF BUS'      | 'MUR'   | 'WBM155R71C104K'    | 'EP(V1)'     | 'EP(V1)'  | 'DISCRETE' | ''      | 'S5M-GLEN'     | 'MUR_LF_CAP SERIES_1.pdf'        | '0402 SERIES_LL34.xls'      | ''            | ''  | ''     | ''      | '20150105'
 'DIFF BUS_0.1UF'  | '16V'   | '10%'     | 'C0402'   | 'EMPTY'  | 'SP_CH4103K1B08'(!) = ''              | ''             | ''       | 'CH4103K1B08' |'C0402_DIFF-BUS'| 'CAP CHIP 0.1U 16V(10%.X7R.0402)_FOR DIFF BUS'      | 'MUR'   | 'WBM155R71C104K'    | 'EP(V1)'     | 'EP(V1)'  | 'DISCRETE' | ''      | 'S5M-GLEN'     | 'MUR_LF_CAP SERIES_1.pdf'        | '0402 SERIES_LL34.xls'      | ''            | ''  | ''     | ''      | '20150105'
 'DIFF BUS_0.22UF' | '6.3V'  | '10%'     | 'C0201'   | 'X5R'    | 'SP_CH4221K9E00'(!) = ''              | ''             | ''       | 'CH4221K9E00' |'C0201_DIFF-BUS'| 'CAP CHIP 0.22UF 6.3V(+-10%,X5R,0201)_FOR DIFF BUS' | 'MUR'   | 'GRM033R60J224K'    | 'EU(V1)'     | ''        | 'DISCRETE' | ''      | 'CJ2A-KEVIN'   | 'AC Coupling.msg'                | 'DCN-all 0201 RCL part.doc' | ''            | ''  | ''     | ''      | '20150511'
 'DIFF BUS_0.22UF' | '6.3V'  | '10%'     | 'C0201'   | 'EMPTY'  | 'SP_CH4221K9E00'(!) = ''              | ''             | ''       | 'CH4221K9E00' |'C0201_DIFF-BUS'| 'CAP CHIP 0.22UF 6.3V(+-10%,X5R,0201)_FOR DIFF BUS' | 'MUR'   | 'GRM033R60J224K'    | 'EU(V1)'     | ''        | 'DISCRETE' | ''      | 'CJ2A-KEVIN'   | 'AC Coupling.msg'                | 'DCN-all 0201 RCL part.doc' | ''            | ''  | ''     | ''      | '20150511'
 'DIFF BUS_0.1UF'  | '16V'   | '10%'     | 'C0402'   | 'X7R'    | 'SP_CH4103K1B14'(!) = 'End of Design' | 'Comp-Approve' | ''       | 'CH4103K1B14' |'C0402_DIFF-BUS'| 'CAP CHIP 0.1U 16V(10%,X7R,0402)MUR'                | 'MUR'   | 'GRM155R71C104K'    | 'EP(V1)'     | ''        | 'DISCRETE' | ''      | 'T2H-CF'       | 'AC Coupling.msg'                | '0402 SERIES_LL34.xls'      | ''            | ''  | ''     | ''      | '20150603'
 'DIFF BUS_0.1UF'  | '16V'   | '10%'     | 'C0402'   | 'EMPTY'  | 'SP_CH4103K1B14'(!) = 'End of Design' | 'Comp-Approve' | ''       | 'CH4103K1B14' |'C0402_DIFF-BUS'| 'CAP CHIP 0.1U 16V(10%,X7R,0402)MUR'                | 'MUR'   | 'GRM155R71C104K'    | 'EP(V1)'     | ''        | 'DISCRETE' | ''      | 'T2H-CF'       | 'AC Coupling.msg'                | '0402 SERIES_LL34.xls'      | ''            | ''  | ''     | ''      | '20150603'
 'DIFF BUS_0.22UF' | '16V'   | '10%'     | 'C0402'   | 'X7R'    | 'SP_CH4223K1B04'(!) = 'End of Design' | 'Comp-Approve' | ''       | 'CH4223K1B04' |'C0402_DIFF-BUS'| 'CAP CHIP 0.22U 16V(10%,X7R,0402)MUR'               | 'MUR'   | 'GRM155R71C224K'    | 'EP(V1)'     | ''        | 'DISCRETE' | ''      | 'T2H-CF'       | 'AC Coupling.msg'                | '0402 SERIES_LL34.xls'      | ''            | ''  | ''     | ''      | '20150603'
 'DIFF BUS_0.22UF' | '16V'   | '10%'     | 'C0402'   | 'EMPTY'  | 'SP_CH4223K1B04'(!) = 'End of Design' | 'Comp-Approve' | ''       | 'CH4223K1B04' |'C0402_DIFF-BUS'| 'CAP CHIP 0.22U 16V(10%,X7R,0402)MUR'               | 'MUR'   | 'GRM155R71C224K'    | 'EP(V1)'     | ''        | 'DISCRETE' | ''      | 'T2H-CF'       | 'AC Coupling.msg'                | '0402 SERIES_LL34.xls'      | ''            | ''  | ''     | ''      | '20150603'
 'DIFF BUS_0.22UF' | '6.3V'  | '20%'     | 'C0201'   | 'X6S'    | 'SP_CH4221MEE01'(!) = ''              | ''             | ''       | 'CH4221MEE01' |'C0201_DIFF-BUS'| 'CAP CHIP 0.22UF 6.3V(20%,X6S,0201)_DIFF BUS'       | 'TDK'   | 'C0603X6S0J224MT-A' | 'EP(V1)'     | 'EP(V1)'  | 'DISCRETE' | ''      | 'CJ2A-KEVIN'   | 'AC Coupling.msg'                | 'DCN-all 0201 RCL part.doc' | ''            | ''  | ''     | ''      | '20150629'
 'DIFF BUS_0.22UF' | '6.3V'  | '20%'     | 'C0201'   | 'EMPTY'  | 'SP_CH4221MEE01'(!) = ''              | ''             | ''       | 'CH4221MEE01' |'C0201_DIFF-BUS'| 'CAP CHIP 0.22UF 6.3V(20%,X6S,0201)_DIFF BUS'       | 'TDK'   | 'C0603X6S0J224MT-A' | 'EP(V1)'     | 'EP(V1)'  | 'DISCRETE' | ''      | 'CJ2A-KEVIN'   | 'AC Coupling.msg'                | 'DCN-all 0201 RCL part.doc' | ''            | ''  | ''     | ''      | '20150629'
 'DIFF BUS_0.22UF' | '16V'   | '10%'     | 'C0402'   | 'X7R'    | 'SP_CH4223K1B06'(!) = ''              | ''             | 'AEC'    | 'CH4223K1B06' |'C0402_DIFF-BUS'| 'CAP CHIP 0.22U 16V(10%,X7R,0402)AEC)_DIFF BUS'     | 'MUR'   | 'GCM155R71C224K'    | 'EP(V1)'     | 'EP(V1)'  | 'DISCRETE' | ''      | 'T2HV-RONNY'   | 'AC Coupling.msg'                | '0402 SERIES_LL34.xls'      | ''            | ''  | ''     | ''      | '20150511'
 'DIFF BUS_0.22UF' | '16V'   | '10%'     | 'C0402'   | 'EMPTY'  | 'SP_CH4223K1B06'(!) = ''              | ''             | 'AEC'    | 'CH4223K1B06' |'C0402_DIFF-BUS'| 'CAP CHIP 0.22U 16V(10%,X7R,0402)AEC)_DIFF BUS'     | 'MUR'   | 'GCM155R71C224K'    | 'EP(V1)'     | 'EP(V1)'  | 'DISCRETE' | ''      | 'T2HV-RONNY'   | 'AC Coupling.msg'                | '0402 SERIES_LL34.xls'      | ''            | ''  | ''     | ''      | '20150511'
 'DIFF BUS_0.1UF'  | '16V'   | '10%'     | 'C0402'   | 'X7R'    | 'SP_CH4103K1B21'(!) = ''              | ''             | 'AEC'    | 'CH4103K1B21' |'C0402_DIFF-BUS'| 'CAP CHIP 0.1U 16V(+-10%,X7R,0402)AEC_DIFF BUS'     | 'YGO'   | 'AC0402KRX7R7BB104' | 'EP(V1)'     | ''        | 'DISCRETE' | ''      | 'T2HV-RONNY'   | 'AC Coupling.msg'                | '0402 SERIES_LL34.xls'      | ''            | ''  | ''     | ''      | '20150511'
 'DIFF BUS_0.1UF'  | '16V'   | '10%'     | 'C0402'   | 'EMPTY'  | 'SP_CH4103K1B21'(!) = ''              | ''             | 'AEC'    | 'CH4103K1B21' |'C0402_DIFF-BUS'| 'CAP CHIP 0.1U 16V(+-10%,X7R,0402)AEC_DIFF BUS'     | 'YGO'   | 'AC0402KRX7R7BB104' | 'EP(V1)'     | ''        | 'DISCRETE' | ''      | 'T2HV-RONNY'   | 'AC Coupling.msg'                | '0402 SERIES_LL34.xls'      | ''            | ''  | ''     | ''      | '20150511'
 'DIFF BUS_0.1UF'  | '16V'   | '10%'     | 'C0402'   | 'X7R'    | 'SP_CH4103K1B22'(!) = 'End of Design' | 'Comp-Approve' | 'AEC'    | 'CH4103K1B22' |'C0402_DIFF-BUS'| 'CAP CHIP 0.1U 16V(10%,X7R,0402)MUR_AEC_DIFF BUS'   | 'MUR'   | 'GCM155R71C104K'    | 'EP(V1)'     | ''        | 'DISCRETE' | ''      | 'T2HV-RONNY'   | ''                               | ''                          | ''            | ''  | ''     | ''      | '20150518'
 'DIFF BUS_0.1UF'  | '16V'   | '10%'     | 'C0402'   | 'EMPTY'  | 'SP_CH4103K1B22'(!) = 'End of Design' | 'Comp-Approve' | 'AEC'    | 'CH4103K1B22' |'C0402_DIFF-BUS'| 'CAP CHIP 0.1U 16V(10%,X7R,0402)MUR_AEC_DIFF BUS'   | 'MUR'   | 'GCM155R71C104K'    | 'EP(V1)'     | ''        | 'DISCRETE' | ''      | 'T2HV-RONNY'   | ''                               | ''                          | ''            | ''  | ''     | ''      | '20150518'
 'DIFF BUS_0.22UF' | '16V'   | '10%'     | 'C0402'   | 'X7R'    | 'SP_CH4223K1B07'(!) = ''              | ''             | 'AEC'    | 'CH4223K1B07' |'C0402_DIFF-BUS'| 'CAP CHIP 0.22U 16V(10%,X7R,0402)MUR_AEC_DIFF BUS'  | 'MUR'   | 'GCM155R71C224K'    | 'EP(V1)'     | ''        | 'DISCRETE' | ''      | 'T2HV-RONNY'   | ''                               | ''                          | ''            | ''  | ''     | ''      | '20150518'
 'DIFF BUS_0.22UF' | '16V'   | '10%'     | 'C0402'   | 'EMPTY'  | 'SP_CH4223K1B07'(!) = ''              | ''             | 'AEC'    | 'CH4223K1B07' |'C0402_DIFF-BUS'| 'CAP CHIP 0.22U 16V(10%,X7R,0402)MUR_AEC_DIFF BUS'  | 'MUR'   | 'GCM155R71C224K'    | 'EP(V1)'     | ''        | 'DISCRETE' | ''      | 'T2HV-RONNY'   | ''                               | ''                          | ''            | ''  | ''     | ''      | '20150518'
 'DIFF BUS_0.33UF' | '6.3V'  | '10%'     | 'C0402'   | 'X6S'    | 'SP_CH4331KEB01'(!) = 'End of Design' | 'Comp-Approve' | ''       | 'CH4331KEB01' |'C0402_DIFF-BUS'| 'CAP CHIP 0.33UF 6.3V(10%,X6S,0402)_FOR DIFF BUS'   | 'MUR'   | 'GRM155C80J334K'    | 'EP(V1)'     | 'EP(V1)'  | 'DISCRETE' | ''      | 'S5R-ROGER'    | ''                               | ''                          | ''            | ''  | ''     | ''      | '20180504'
 'DIFF BUS_0.33UF' | '6.3V'  | '10%'     | 'C0402'   | 'EMPTY'  | 'SP_CH4331KEB01'(!) = 'End of Design' | 'Comp-Approve' | ''       | 'CH4331KEB01' |'C0402_DIFF-BUS'| 'CAP CHIP 0.33UF 6.3V(10%,X6S,0402)_FOR DIFF BUS'   | 'MUR'   | 'GRM155C80J334K'    | 'EP(V1)'     | 'EP(V1)'  | 'DISCRETE' | ''      | 'S5R-ROGER'    | ''                               | ''                          | ''            | ''  | ''     | ''      | '20180504'
 'DIFF BUS_0.01UF' | '16V'   | '10%'     | 'C0402'   | 'X7R'    | 'SP_CH3103K1B15_3'(!) = 'End of Design' | 'Comp-Approve' | ''       | 'CH3103K1B15' |'C0402_DIFF-BUS'| 'CAP CHIP 0.01U 16V(10%,X7R,0402)_FOR DIFF BUS'     | 'MUR'   | 'GRM155R71C103K'    | 'EP(V1)'     | 'EP(V1)'  | 'DISCRETE' | ''      | 'S5R-ROGER'    | ''                               | ''                          | ''            | ''  | ''     | ''      | '20180516'
 'DIFF BUS_0.01UF' | '16V'   | '10%'     | 'C0402'   | 'EMPTY'  | 'SP_CH3103K1B15_3'(!) = 'End of Design' | 'Comp-Approve' | ''       | 'CH3103K1B15' |'C0402_DIFF-BUS'| 'CAP CHIP 0.01U 16V(10%,X7R,0402)_FOR DIFF BUS'     | 'MUR'   | 'GRM155R71C103K'    | 'EP(V1)'     | 'EP(V1)'  | 'DISCRETE' | ''      | 'S5R-ROGER'    | ''                               | ''                          | ''            | ''  | ''     | ''      | '20180516'
 'DIFF BUS_0.22UF' | '6.3V'  | '10%'     | 'C0201'   | 'X6S'    | 'SP_CH4221KEE00'(!) = ''              | ''             | ''       | 'CH4221KEE00' |'C0201_DIFF-BUS'| 'CAP CHIP 0.22UF 6.3V(+-10%,X6S,0201)_DIFF BUS'     | 'MUR'   | 'GRM033C80J224K'    | 'EP(V1)'     | 'EP(V1)'  | 'DISCRETE' | ''      | 'T2M-MARK'     | 'AC Coupling.msg'                | 'DCN-all 0201 RCL part.doc' | ''            | ''  | ''     | ''      | '20190827'
 'DIFF BUS_0.22UF' | '6.3V'  | '10%'     | 'C0201'   | 'EMPTY'  | 'SP_CH4221KEE00'(!) = ''              | ''             | ''       | 'CH4221KEE00' |'C0201_DIFF-BUS'| 'CAP CHIP 0.22UF 6.3V(+-10%,X6S,0201)_DIFF BUS'     | 'MUR'   | 'GRM033C80J224K'    | 'EP(V1)'     | 'EP(V1)'  | 'DISCRETE' | ''      | 'T2M-MARK'     | 'AC Coupling.msg'                | 'DCN-all 0201 RCL part.doc' | ''            | ''  | ''     | ''      | '20190827'
 'DIFF BUS_0.1UF'  | '6.3V'  | '10%'     | 'C0201'   | 'X6S'    | 'SP_CH4101KEE02'(!) = ''              | ''             | ''       | 'CH4101KEE02' |'C0201_DIFF-BUS'| 'CAP CHIP 0.1UF 6.3V(10%,X6S,0201)SAM_DIFF BUS'     | 'SAM'   | 'CL03X104KQ3NNNC'   | 'EP(V1)'     | 'EP(V1)'  | 'DISCRETE' | ''      | 'S8I-KATE'     | 'AC Coupling.msg'                | 'DCN-all 0201 RCL part.doc' | ''            | ''  | ''     | ''      | '20191008'
 'DIFF BUS_0.1UF'  | '6.3V'  | '10%'     | 'C0201'   | 'EMPTY'  | 'SP_CH4101KEE02'(!) = ''              | ''             | ''       | 'CH4101KEE02' |'C0201_DIFF-BUS'| 'CAP CHIP 0.1UF 6.3V(10%,X6S,0201)SAM_DIFF BUS'     | 'SAM'   | 'CL03X104KQ3NNNC'   | 'EP(V1)'     | 'EP(V1)'  | 'DISCRETE' | ''      | 'S8I-KATE'     | 'AC Coupling.msg'                | 'DCN-all 0201 RCL part.doc' | ''            | ''  | ''     | ''      | '20191008'
 'DIFF BUS_0.22UF' | '6.3V'  | '10%'     | 'C0201'   | 'X6S'    | 'SP_CH4221KEE01'(!) = ''              | ''             | ''       | 'CH4221KEE01' |'C0201_DIFF-BUS'| 'CAP CHIP 0.22UF 6.3V(+-10%,X6S,0201)MUR_DIFF BUS'  | 'MUR'   | 'GRM033C80J224K'    | 'EP(V1)'     | 'EP(V1)'  | 'DISCRETE' | ''      | 'S8I-KATE'     | 'AC Coupling.msg'                | 'DCN-all 0201 RCL part.doc' | ''            | ''  | ''     | ''      | '20200224'
 'DIFF BUS_0.22UF' | '6.3V'  | '10%'     | 'C0201'   | 'EMPTY'  | 'SP_CH4221KEE01'(!) = ''              | ''             | ''       | 'CH4221KEE01' |'C0201_DIFF-BUS'| 'CAP CHIP 0.22UF 6.3V(+-10%,X6S,0201)MUR_DIFF BUS'  | 'MUR'   | 'GRM033C80J224K'    | 'EP(V1)'     | 'EP(V1)'  | 'DISCRETE' | ''      | 'S8I-KATE'     | 'AC Coupling.msg'                | 'DCN-all 0201 RCL part.doc' | ''            | ''  | ''     | ''      | '20200224'
 'DIFF BUS_0.22UF' | '6.3V'  | '10%'     | 'C0201'   | 'X6S'    | 'SP_CH4221KEE04'(!) = ''              | ''             | ''       | 'CH4221KEE04' |'C0201_DIFF-BUS'| 'CAP CHIP 0.22UF 6.3V(+-10%,X6S,0201)SAM_DIFF BUS'  | 'SAM'   | 'CL03X224KQ3NNWC'   | 'EP(V1)'     | 'EP(V1)'  | 'DISCRETE' | ''      | 'T6H-WILLY'    | 'AC Coupling.msg'                | 'DCN-all 0201 RCL part.doc' | ''            | ''  | ''     | ''      | '20221024'
 'DIFF BUS_0.22UF' | '6.3V'  | '10%'     | 'C0201'   | 'EMPTY'  | 'SP_CH4221KEE04'(!) = ''              | ''             | ''       | 'CH4221KEE04' |'C0201_DIFF-BUS'| 'CAP CHIP 0.22UF 6.3V(+-10%,X6S,0201)SAM_DIFF BUS'  | 'SAM'   | 'CL03X224KQ3NNWC'   | 'EP(V1)'     | 'EP(V1)'  | 'DISCRETE' | ''      | 'T6H-WILLY'    | 'AC Coupling.msg'                | 'DCN-all 0201 RCL part.doc' | ''            | ''  | ''     | ''      | '20221024'
 'DIFF BUS_0.33UF' | '6.3V'  | '10%'     | 'C0402'   | 'X6S'    | 'SP_CH4331KEB03'(!) = ''              | ''               | ''       | 'CH4331KEB03' |'C0402_DIFF-BUS'| 'CAP CHIP 0.33U 6.3V(+-10%,X6S,0402)API_DIFF BUS'   | 'API'   | 'C1005X6S334KCT'    | 'EP(V1)'     | 'EP(V1)'  | 'DISCRETE' | ''      | 'T6H-WILLY'    | 'API_C1005X6S334KCT.pdf'         | '0402 SERIES_LL34.xls'      | ''            | ''  | ''     | ''      | '20230207'
 'DIFF BUS_0.33UF' | '6.3V'  | '10%'     | 'C0402'   | 'EMPTY'  | 'SP_CH4331KEB03'(!) = ''              | ''               | ''       | 'CH4331KEB03' |'C0402_DIFF-BUS'| 'CAP CHIP 0.33U 6.3V(+-10%,X6S,0402)API_DIFF BUS'   | 'API'   | 'C1005X6S334KCT'    | 'EP(V1)'     | 'EP(V1)'  | 'DISCRETE' | ''      | 'T6H-WILLY'    | 'API_C1005X6S334KCT.pdf'         | '0402 SERIES_LL34.xls'      | ''            | ''  | ''     | ''      | '20230207'

END_PART

END.

